# S9S_MB_2U (Grand Teton) — schematic netlist excerpt (pin names and nets, part order shuffled) for the footprints in the layout excerpt that follows; sources: Cadence DE-HDL packaged netlist, KiCad conversion of 03242023_DA0F0TMBIJ0_F0T_Motherboard_J_brd_V01_OCP.brd

R2366  Q_RES  0 5% CHIP  pkg 0402LF  page 266 : A = PWRGD_PVCCIN_CPU0 ; B = PWRGD_PVCCIN_CPU0_R

U306  GTL2014PW  IC  pkg TSSOP14  page 225
  DIR  = PD_CPU1_ERRS_U306_DIR
  B0  = PD_GTL2014_ERROR_B0
  B1  = H_CPU_ERR2_LVC1_N
  VREF  = P0V62_CPU0_ERRS_U306_VREF
  B2  = H_CPU_ERR1_LVC1_N
  B3  = H_CPU_ERR0_LVC1_N
  GND_0  = GND
  GND_1  = GND
  A3  = H_CPU_ERR0_LVC2_R_N
  A2  = H_CPU_ERR1_LVC2_R_N
  GND_2  = GND
  A1  = H_CPU_ERR2_LVC2_R_N
  A0  = NC_U306_A0
  VCC  = P3V3

(kicad_pcb
	(version 20260206)
	(generator "pcbnew")
	(generator_version "10.0")
	(general
		(thickness 1.6)
		(legacy_teardrops no)
	)
	(paper "A4")
	(title_block
		(title "03242023_DA0F0TMBIJ0_F0T_Motherboard_J_brd_V01_OCP.brd")
		(comment 1 "Grand Teton / footprints 293-294 of 6105")
	)
	(layers
		(0 "F.Cu" signal "TOP")
		(4 "In1.Cu" signal "GND")
		(6 "In2.Cu" signal "IN1")
		(8 "In3.Cu" signal "GND1")
		(10 "In4.Cu" signal "IN2")
		(12 "In5.Cu" signal "GND2")
		(14 "In6.Cu" signal "IN3")
		(16 "In7.Cu" signal "GND3")
		(18 "In8.Cu" signal "VCC")
		(20 "In9.Cu" signal "VCC1")
		(22 "In10.Cu" signal "GND4")
		(24 "In11.Cu" signal "IN4")
		(26 "In12.Cu" signal "GND5")
		(28 "In13.Cu" signal "IN5")
		(30 "In14.Cu" signal "GND6")
		(32 "In15.Cu" signal "IN6")
		(34 "In16.Cu" signal "GND7")
		(2 "B.Cu" signal "BOTTOM")
		(9 "F.Adhes" user "F.Adhesive")
		(11 "B.Adhes" user "B.Adhesive")
		(13 "F.Paste" user "Package Geometry/Pastemask Top")
		(15 "B.Paste" user "Package Geometry/Pastemask Bottom")
		(5 "F.SilkS" user "Ref Des/Silkscreen Top")
		(7 "B.SilkS" user "Ref Des/Silkscreen Bottom")
		(1 "F.Mask" user "Board Geometry/Soldermask Top")
		(3 "B.Mask" user "Board Geometry/Soldermask Bottom")
		(17 "Dwgs.User" user "User.Drawings")
		(19 "Cmts.User" user "User.Comments")
		(21 "Eco1.User" user "User.Eco1")
		(23 "Eco2.User" user "User.Eco2")
		(25 "Edge.Cuts" user "Board Geometry/Outline")
		(27 "Margin" user)
		(31 "F.CrtYd" user "Package Geometry/Place Bound Top")
		(29 "B.CrtYd" user "Package Geometry/Place Bound Bottom")
		(35 "F.Fab" user "Ref Des/Assembly Top")
		(33 "B.Fab" user "Ref Des/Assembly Bottom")
	)
	(footprint ""
		(layer "F.Cu")
		(at 141.656054 -97.808542 -90)
		(property "Reference" "U306"
			(at -1.20523 -2.996692 0)
			(unlocked yes)
			(layer "F.SilkS")
			(effects
				(font
					(size 0.7874 0.5842)
					(thickness 0.1524)
				)
				(justify left)
			)
		)
		(property "Value" ""
			(at 0 0 270)
			(layer "F.Fab")
			(effects
				(font
					(size 1.27 1.27)
				)
			)
		)
		(duplicate_pad_numbers_are_jumpers no)
		(fp_line
			(start -2.0066 2.5527)
			(end -2.0066 -2.5527)
			(stroke
				(width 0.1524)
				(type default)
			)
			(layer "F.SilkS")
		)
		(fp_line
			(start 2.0066 2.5527)
			(end -2.0066 2.5527)
			(stroke
				(width 0.1524)
				(type default)
			)
			(layer "F.SilkS")
		)
		(fp_line
			(start 0 -1.9812)
			(end 0.5715 -2.5527)
			(stroke
				(width 0.1524)
				(type default)
			)
			(layer "F.SilkS")
		)
		(fp_line
			(start -2.0066 -2.5527)
			(end -0.5715 -2.5527)
			(stroke
				(width 0.1524)
				(type default)
			)
			(layer "F.SilkS")
		)
		(fp_line
			(start -0.5715 -2.5527)
			(end 0 -1.9812)
			(stroke
				(width 0.1524)
				(type default)
			)
			(layer "F.SilkS")
		)
		(fp_line
			(start 0.5715 -2.5527)
			(end 2.0066 -2.5527)
			(stroke
				(width 0.1524)
				(type default)
			)
			(layer "F.SilkS")
		)
		(fp_line
			(start 2.0066 -2.5527)
			(end 2.0066 2.5527)
			(stroke
				(width 0.1524)
				(type default)
			)
			(layer "F.SilkS")
		)
		(fp_poly
			(pts
				(xy -2.810764 -2.90576) (xy -3.138932 -2.35204) (xy -3.435604 -2.90576)
			)
			(stroke
				(width 0)
				(type default)
			)
			(fill yes)
			(layer "F.SilkS")
		)
		(fp_line
			(start -2.249932 2.549906)
			(end -2.249932 -2.549906)
			(stroke
				(width 0.1)
				(type default)
			)
			(layer "F.Fab")
		)
		(fp_line
			(start 2.249932 2.549906)
			(end -2.249932 2.549906)
			(stroke
				(width 0.1)
				(type default)
			)
			(layer "F.Fab")
		)
		(fp_line
			(start -2.249932 -2.549906)
			(end 2.249932 -2.549906)
			(stroke
				(width 0.1)
				(type default)
			)
			(layer "F.Fab")
		)
		(fp_line
			(start 2.249932 -2.549906)
			(end 2.249932 2.549906)
			(stroke
				(width 0.1)
				(type default)
			)
			(layer "F.Fab")
		)
		(fp_poly
			(pts
				(xy -4.36372 -1.608328) (xy -4.36372 -2.233168) (xy -3.81 -1.905)
			)
			(stroke
				(width 0)
				(type default)
			)
			(fill yes)
			(layer "F.Fab")
		)
		(pad "1" smd rect
			(at -2.921 -1.949958 180)
			(size 0.3556 1.4986)
			(layers "F.Cu" "F.Mask" "F.Paste")
			(net "PD_CPU1_ERRS_U306_DIR")
		)
		(pad "2" smd rect
			(at -2.921 -1.299972 180)
			(size 0.3556 1.4986)
			(layers "F.Cu" "F.Mask" "F.Paste")
			(net "PD_GTL2014_ERROR_B0")
		)
		(pad "3" smd rect
			(at -2.921 -0.649986 180)
			(size 0.3556 1.4986)
			(layers "F.Cu" "F.Mask" "F.Paste")
			(net "H_CPU_ERR2_LVC1_N")
		)
		(pad "4" smd rect
			(at -2.921 0 180)
			(size 0.3556 1.4986)
			(layers "F.Cu" "F.Mask" "F.Paste")
			(net "P0V62_CPU0_ERRS_U306_VREF")
		)
		(pad "5" smd rect
			(at -2.921 0.649986 180)
			(size 0.3556 1.4986)
			(layers "F.Cu" "F.Mask" "F.Paste")
			(net "H_CPU_ERR1_LVC1_N")
		)
		(pad "6" smd rect
			(at -2.921 1.299972 180)
			(size 0.3556 1.4986)
			(layers "F.Cu" "F.Mask" "F.Paste")
			(net "H_CPU_ERR0_LVC1_N")
		)
		(pad "7" smd rect
			(at -2.921 1.949958 180)
			(size 0.3556 1.4986)
			(layers "F.Cu" "F.Mask" "F.Paste")
			(net "GND")
		)
		(pad "8" smd rect
			(at 2.921 1.949958 180)
			(size 0.3556 1.4986)
			(layers "F.Cu" "F.Mask" "F.Paste")
			(net "GND")
		)
		(pad "9" smd rect
			(at 2.921 1.299972 180)
			(size 0.3556 1.4986)
			(layers "F.Cu" "F.Mask" "F.Paste")
			(net "H_CPU_ERR0_LVC2_R_N")
		)
		(pad "10" smd rect
			(at 2.921 0.649986 180)
			(size 0.3556 1.4986)
			(layers "F.Cu" "F.Mask" "F.Paste")
			(net "H_CPU_ERR1_LVC2_R_N")
		)
		(pad "11" smd rect
			(at 2.921 0 180)
			(size 0.3556 1.4986)
			(layers "F.Cu" "F.Mask" "F.Paste")
			(net "GND")
		)
		(pad "12" smd rect
			(at 2.921 -0.649986 180)
			(size 0.3556 1.4986)
			(layers "F.Cu" "F.Mask" "F.Paste")
			(net "H_CPU_ERR2_LVC2_R_N")
		)
		(pad "13" smd rect
			(at 2.921 -1.299972 180)
			(size 0.3556 1.4986)
			(layers "F.Cu" "F.Mask" "F.Paste")
			(net "NC_U306_A0")
		)
		(pad "14" smd rect
			(at 2.921 -1.949958 180)
			(size 0.3556 1.4986)
			(layers "F.Cu" "F.Mask" "F.Paste")
			(net "P3V3")
		)
	)
	(footprint ""
		(layer "F.Cu")
		(at 349.77705 -360.929174 -90)
		(property "Reference" "R2366"
			(at 0 0 270)
			(layer "F.SilkS")
			(hide yes)
			(effects
				(font
					(size 1.27 1.27)
				)
			)
		)
		(property "Value" ""
			(at 0 0 270)
			(layer "F.Fab")
			(effects
				(font
					(size 1.27 1.27)
				)
			)
		)
		(duplicate_pad_numbers_are_jumpers no)
		(fp_line
			(start -0.7874 0.4064)
			(end -0.7874 -0.4064)
			(stroke
				(width 0.1524)
				(type default)
			)
			(layer "F.SilkS")
		)
		(fp_line
			(start 0.7874 0.4064)
			(end -0.7874 0.4064)
			(stroke
				(width 0.1524)
				(type default)
			)
			(layer "F.SilkS")
		)
		(fp_line
			(start -0.7874 -0.4064)
			(end 0.7874 -0.4064)
			(stroke
				(width 0.1524)
				(type default)
			)
			(layer "F.SilkS")
		)
		(fp_line
			(start 0.7874 -0.4064)
			(end 0.7874 0.4064)
			(stroke
				(width 0.1524)
				(type default)
			)
			(layer "F.SilkS")
		)
		(fp_line
			(start -0.67945 0.3048)
			(end -0.67945 -0.305054)
			(stroke
				(width 0.1)
				(type default)
			)
			(layer "F.Fab")
		)
		(fp_line
			(start -0.12065 0.3048)
			(end -0.67945 0.3048)
			(stroke
				(width 0.1)
				(type default)
			)
			(layer "F.Fab")
		)
		(fp_line
			(start 0.120396 0.3048)
			(end 0.120396 0.2794)
			(stroke
				(width 0.1)
				(type default)
			)
			(layer "F.Fab")
		)
		(fp_line
			(start 0.67945 0.3048)
			(end 0.120396 0.3048)
			(stroke
				(width 0.1)
				(type default)
			)
			(layer "F.Fab")
		)
		(fp_line
			(start -0.12065 0.2794)
			(end -0.12065 0.3048)
			(stroke
				(width 0.1)
				(type default)
			)
			(layer "F.Fab")
		)
		(fp_line
			(start 0.120396 0.2794)
			(end -0.12065 0.2794)
			(stroke
				(width 0.1)
				(type default)
			)
			(layer "F.Fab")
		)
		(fp_line
			(start -0.12065 -0.2794)
			(end 0.12065 -0.2794)
			(stroke
				(width 0.1)
				(type default)
			)
			(layer "F.Fab")
		)
		(fp_line
			(start 0.12065 -0.2794)
			(end 0.12065 -0.3048)
			(stroke
				(width 0.1)
				(type default)
			)
			(layer "F.Fab")
		)
		(fp_line
			(start 0.12065 -0.3048)
			(end 0.67945 -0.3048)
			(stroke
				(width 0.1)
				(type default)
			)
			(layer "F.Fab")
		)
		(fp_line
			(start 0.67945 -0.3048)
			(end 0.67945 0.3048)
			(stroke
				(width 0.1)
				(type default)
			)
			(layer "F.Fab")
		)
		(fp_line
			(start -0.67945 -0.305054)
			(end -0.12065 -0.305054)
			(stroke
				(width 0.1)
				(type default)
			)
			(layer "F.Fab")
		)
		(fp_line
			(start -0.12065 -0.305054)
			(end -0.12065 -0.2794)
			(stroke
				(width 0.1)
				(type default)
			)
			(layer "F.Fab")
		)
		(pad "1" smd circle
			(at -0.40005 0 270)
			(size 0 0)
			(layers "F.Cu" "F.Mask" "F.Paste")
			(net "PWRGD_PVCCIN_CPU0")
		)
		(pad "2" smd circle
			(at 0.40005 0 270)
			(size 0 0)
			(layers "F.Cu" "F.Mask" "F.Paste")
			(net "PWRGD_PVCCIN_CPU0_R")
		)
	)
)
